# BASEBOARD_FAB2 (Tioga Pass) — schematic netlist excerpt (pin names and nets, part order shuffled) for the footprints in the layout excerpt that follows; sources: Cadence DE-HDL packaged netlist, KiCad conversion of Wiwynn_Tioga_Pass_MB.brd

R7P12  RES  42.2 1.0% EMPTY  pkg 0402  page 103 : A = CLK_100M_CPU1_RC_REFCLK1_DN ; B = GND
C2R5  CAP_A  0.1UF 16V 10% X7R  pkg 0402V  page 192 : A = P3V3_STBY ; B = GND
R8D37  RES  4.75K 1% CHIP  pkg 0402  page 196 : A = A_PG_P5V ; B = GND

(kicad_pcb
	(version 20260206)
	(generator "pcbnew")
	(generator_version "10.0")
	(general
		(thickness 1.6)
		(legacy_teardrops no)
	)
	(paper "A4")
	(title_block
		(title "Wiwynn_Tioga_Pass_MB.brd")
		(comment 1 "Tioga Pass / footprints 3634-3636 of 4770")
	)
	(layers
		(0 "F.Cu" signal "TOP")
		(4 "In1.Cu" signal "L2GND")
		(6 "In2.Cu" signal "L3")
		(8 "In3.Cu" signal "L4GND")
		(10 "In4.Cu" signal "L5")
		(12 "In5.Cu" signal "L6GND")
		(14 "In6.Cu" signal "L7VCC")
		(16 "In7.Cu" signal "L8VCC")
		(18 "In8.Cu" signal "L9GND")
		(20 "In9.Cu" signal "L10")
		(22 "In10.Cu" signal "L11GND")
		(24 "In11.Cu" signal "L12")
		(26 "In12.Cu" signal "L13GND")
		(2 "B.Cu" signal "BOTTOM")
		(9 "F.Adhes" user "F.Adhesive")
		(11 "B.Adhes" user "B.Adhesive")
		(13 "F.Paste" user "Package Geometry/Pastemask Top")
		(15 "B.Paste" user "Package Geometry/Pastemask Bottom")
		(5 "F.SilkS" user "Ref Des/Silkscreen Top")
		(7 "B.SilkS" user "Ref Des/Silkscreen Bottom")
		(1 "F.Mask" user "Board Geometry/Soldermask Top")
		(3 "B.Mask" user "Board Geometry/Soldermask Bottom")
		(17 "Dwgs.User" user "User.Drawings")
		(19 "Cmts.User" user "User.Comments")
		(21 "Eco1.User" user "User.Eco1")
		(23 "Eco2.User" user "User.Eco2")
		(25 "Edge.Cuts" user "Board Geometry/Outline")
		(27 "Margin" user)
		(31 "F.CrtYd" user "Package Geometry/Place Bound Top")
		(29 "B.CrtYd" user "Package Geometry/Place Bound Bottom")
		(35 "F.Fab" user "Ref Des/Assembly Top")
		(33 "B.Fab" user "Ref Des/Assembly Bottom")
	)
	(footprint ""
		(layer "B.Cu")
		(at 373.944642 -72.295512 180)
		(property "Reference" "C2R5"
			(at 0 0 0)
			(layer "B.SilkS")
			(hide yes)
			(effects
				(font
					(size 1.27 1.27)
				)
				(justify mirror)
			)
		)
		(property "Value" ""
			(at 0 0 0)
			(layer "B.Fab")
			(effects
				(font
					(size 1.27 1.27)
				)
				(justify mirror)
			)
		)
		(duplicate_pad_numbers_are_jumpers no)
		(fp_rect
			(start 0.2794 0.9144)
			(end -0.2794 -0.1143)
			(stroke
				(width 0)
				(type default)
			)
			(fill no)
			(layer "B.CrtYd")
		)
		(fp_line
			(start 0.2794 0.9144)
			(end 0.2794 -0.1143)
			(stroke
				(width 0.1)
				(type default)
			)
			(layer "B.Fab")
		)
		(fp_line
			(start 0.2794 -0.1143)
			(end -0.2794 -0.1143)
			(stroke
				(width 0.1)
				(type default)
			)
			(layer "B.Fab")
		)
		(fp_line
			(start -0.2794 0.9144)
			(end 0.2794 0.9144)
			(stroke
				(width 0.1)
				(type default)
			)
			(layer "B.Fab")
		)
		(fp_line
			(start -0.2794 -0.1143)
			(end -0.2794 0.9144)
			(stroke
				(width 0.1)
				(type default)
			)
			(layer "B.Fab")
		)
		(pad "1" smd custom
			(at 0 0 90)
			(size 0.10414 0.10414)
			(layers "B.Cu" "B.Mask" "B.Paste")
			(net "P3V3_STBY")
			(options
				(clearance outline)
				(anchor circle)
			)
			(primitives
				(gr_poly
					(pts
						(xy -0.20828 -0.08636) (xy -0.20828 0.08636) (xy -0.08636 0.20828) (xy 0.086614 0.20828) (xy 0.20828 0.086614)
						(xy 0.20828 -0.08636) (xy 0.08636 -0.20828) (xy -0.08636 -0.20828)
					)
					(width 0)
					(fill yes)
				)
			)
		)
		(pad "2" smd custom
			(at 0 0.8001 90)
			(size 0.10414 0.10414)
			(layers "B.Cu" "B.Mask" "B.Paste")
			(net "GND")
			(options
				(clearance outline)
				(anchor circle)
			)
			(primitives
				(gr_poly
					(pts
						(xy -0.20828 -0.08636) (xy -0.20828 0.08636) (xy -0.08636 0.20828) (xy 0.086614 0.20828) (xy 0.20828 0.086614)
						(xy 0.20828 -0.08636) (xy 0.08636 -0.20828) (xy -0.08636 -0.20828)
					)
					(width 0)
					(fill yes)
				)
			)
		)
		(zone
			(layer "B.Cu")
			(hatch none 0.5)
			(connect_pads
				(clearance 0)
			)
			(min_thickness 0.25)
			(keepout
				(tracks not_allowed)
				(vias allowed)
				(pads allowed)
				(copperpour not_allowed)
				(footprints allowed)
			)
			(placement
				(enabled no)
				(sheetname "")
			)
			(fill
				(thermal_gap 0.5)
				(thermal_bridge_width 0.5)
				(island_removal_mode 0)
			)
			(polygon
				(pts
					(xy 373.857012 -72.505062) (xy 373.857012 -72.886062) (xy 374.032272 -72.886062) (xy 374.032526 -72.505062)
				)
			)
		)
		(zone
			(layer "B.Cu")
			(hatch none 0.5)
			(connect_pads
				(clearance 0)
			)
			(min_thickness 0.25)
			(keepout
				(tracks allowed)
				(vias not_allowed)
				(pads allowed)
				(copperpour not_allowed)
				(footprints allowed)
			)
			(placement
				(enabled no)
				(sheetname "")
			)
			(fill
				(thermal_gap 0.5)
				(thermal_bridge_width 0.5)
				(island_removal_mode 0)
			)
			(polygon
				(pts
					(xy 373.857012 -72.505062) (xy 373.857012 -72.886062) (xy 374.032272 -72.886062) (xy 374.032526 -72.505062)
				)
			)
		)
	)
	(footprint ""
		(layer "B.Cu")
		(at 408.8765 -4.572 90)
		(property "Reference" "R8D37"
			(at 0 0 90)
			(layer "B.SilkS")
			(hide yes)
			(effects
				(font
					(size 1.27 1.27)
				)
				(justify mirror)
			)
		)
		(property "Value" ""
			(at 0 0 90)
			(layer "B.Fab")
			(effects
				(font
					(size 1.27 1.27)
				)
				(justify mirror)
			)
		)
		(duplicate_pad_numbers_are_jumpers no)
		(fp_poly
			(pts
				(xy 0.2794 -0.1016) (xy -0.2794 -0.1016) (xy -0.2794 0.9906) (xy 0.2794 0.9906)
			)
			(stroke
				(width 0)
				(type default)
			)
			(fill no)
			(layer "B.CrtYd")
		)
		(fp_line
			(start 0.2794 -0.1016)
			(end 0.2794 0.9906)
			(stroke
				(width 0.1)
				(type default)
			)
			(layer "B.Fab")
		)
		(fp_line
			(start -0.2794 -0.1016)
			(end 0.2794 -0.1016)
			(stroke
				(width 0.1)
				(type default)
			)
			(layer "B.Fab")
		)
		(fp_line
			(start 0.2794 0.9906)
			(end -0.2794 0.9906)
			(stroke
				(width 0.1)
				(type default)
			)
			(layer "B.Fab")
		)
		(fp_line
			(start -0.2794 0.9906)
			(end -0.2794 -0.1016)
			(stroke
				(width 0.1)
				(type default)
			)
			(layer "B.Fab")
		)
		(pad "1" smd rect
			(at 0 0 270)
			(size 0.508 0.508)
			(layers "B.Cu" "B.Mask" "B.Paste")
			(net "A_PG_P5V")
		)
		(pad "2" smd rect
			(at 0 0.889 270)
			(size 0.508 0.508)
			(layers "B.Cu" "B.Mask" "B.Paste")
			(net "GND")
		)
		(zone
			(layer "B.Cu")
			(hatch none 0.5)
			(connect_pads
				(clearance 0)
			)
			(min_thickness 0.25)
			(keepout
				(tracks allowed)
				(vias not_allowed)
				(pads allowed)
				(copperpour not_allowed)
				(footprints allowed)
			)
			(placement
				(enabled no)
				(sheetname "")
			)
			(fill
				(thermal_gap 0.5)
				(thermal_bridge_width 0.5)
				(island_removal_mode 0)
			)
			(polygon
				(pts
					(xy 409.1305 -4.826) (xy 409.1305 -4.318) (xy 409.5115 -4.318) (xy 409.5115 -4.826)
				)
			)
		)
		(zone
			(layer "B.Cu")
			(hatch none 0.5)
			(connect_pads
				(clearance 0)
			)
			(min_thickness 0.25)
			(keepout
				(tracks not_allowed)
				(vias allowed)
				(pads allowed)
				(copperpour not_allowed)
				(footprints allowed)
			)
			(placement
				(enabled no)
				(sheetname "")
			)
			(fill
				(thermal_gap 0.5)
				(thermal_bridge_width 0.5)
				(island_removal_mode 0)
			)
			(polygon
				(pts
					(xy 409.5115 -4.826) (xy 409.5115 -4.318) (xy 409.1305 -4.318) (xy 409.1305 -4.826)
				)
			)
		)
	)
	(footprint ""
		(layer "B.Cu")
		(at 162.7886 -76.708 90)
		(property "Reference" "R7P12"
			(at 0 0 90)
			(layer "B.SilkS")
			(hide yes)
			(effects
				(font
					(size 1.27 1.27)
				)
				(justify mirror)
			)
		)
		(property "Value" ""
			(at 0 0 90)
			(layer "B.Fab")
			(effects
				(font
					(size 1.27 1.27)
				)
				(justify mirror)
			)
		)
		(duplicate_pad_numbers_are_jumpers no)
		(fp_poly
			(pts
				(xy 0.2794 -0.1016) (xy -0.2794 -0.1016) (xy -0.2794 0.9906) (xy 0.2794 0.9906)
			)
			(stroke
				(width 0)
				(type default)
			)
			(fill no)
			(layer "B.CrtYd")
		)
		(fp_line
			(start 0.2794 -0.1016)
			(end 0.2794 0.9906)
			(stroke
				(width 0.1)
				(type default)
			)
			(layer "B.Fab")
		)
		(fp_line
			(start -0.2794 -0.1016)
			(end 0.2794 -0.1016)
			(stroke
				(width 0.1)
				(type default)
			)
			(layer "B.Fab")
		)
		(fp_line
			(start 0.2794 0.9906)
			(end -0.2794 0.9906)
			(stroke
				(width 0.1)
				(type default)
			)
			(layer "B.Fab")
		)
		(fp_line
			(start -0.2794 0.9906)
			(end -0.2794 -0.1016)
			(stroke
				(width 0.1)
				(type default)
			)
			(layer "B.Fab")
		)
		(pad "1" smd rect
			(at 0 0 270)
			(size 0.508 0.508)
			(layers "B.Cu" "B.Mask" "B.Paste")
			(net "CLK_100M_CPU1_RC_REFCLK1_DN")
		)
		(pad "2" smd rect
			(at 0 0.889 270)
			(size 0.508 0.508)
			(layers "B.Cu" "B.Mask" "B.Paste")
			(net "GND")
		)
		(zone
			(layer "B.Cu")
			(hatch none 0.5)
			(connect_pads
				(clearance 0)
			)
			(min_thickness 0.25)
			(keepout
				(tracks allowed)
				(vias not_allowed)
				(pads allowed)
				(copperpour not_allowed)
				(footprints allowed)
			)
			(placement
				(enabled no)
				(sheetname "")
			)
			(fill
				(thermal_gap 0.5)
				(thermal_bridge_width 0.5)
				(island_removal_mode 0)
			)
			(polygon
				(pts
					(xy 163.0426 -76.962) (xy 163.0426 -76.454) (xy 163.4236 -76.454) (xy 163.4236 -76.962)
				)
			)
		)
		(zone
			(layer "B.Cu")
			(hatch none 0.5)
			(connect_pads
				(clearance 0)
			)
			(min_thickness 0.25)
			(keepout
				(tracks not_allowed)
				(vias allowed)
				(pads allowed)
				(copperpour not_allowed)
				(footprints allowed)
			)
			(placement
				(enabled no)
				(sheetname "")
			)
			(fill
				(thermal_gap 0.5)
				(thermal_bridge_width 0.5)
				(island_removal_mode 0)
			)
			(polygon
				(pts
					(xy 163.4236 -76.962) (xy 163.4236 -76.454) (xy 163.0426 -76.454) (xy 163.0426 -76.962)
				)
			)
		)
	)
)
